(kicad_pcb
	(version 20260206)
	(generator "pcbnew")
	(generator_version "10.0")
	(general
		(thickness 1.6)
		(legacy_teardrops no)
	)
	(paper "A4")
	(title_block
		(title "Bryce Canyon_IOM_M2_16342-2_OCP.brd")
		(comment 1 "Bryce Canyon / footprints 1-7 of 1146")
	)
	(layers
		(0 "F.Cu" signal "TOP")
		(4 "In1.Cu" signal "L2GND")
		(6 "In2.Cu" signal "L3")
		(8 "In3.Cu" signal "L4VCC")
		(10 "In4.Cu" signal "L5VCC")
		(12 "In5.Cu" signal "L6")
		(14 "In6.Cu" signal "L7GND")
		(2 "B.Cu" signal "BOTTOM")
		(9 "F.Adhes" user "F.Adhesive")
		(11 "B.Adhes" user "B.Adhesive")
		(13 "F.Paste" user "Package Geometry/Pastemask Top")
		(15 "B.Paste" user "Package Geometry/Pastemask Bottom")
		(5 "F.SilkS" user "Ref Des/Silkscreen Top")
		(7 "B.SilkS" user "Ref Des/Silkscreen Bottom")
		(1 "F.Mask" user "Board Geometry/Soldermask Top")
		(3 "B.Mask" user "Board Geometry/Soldermask Bottom")
		(17 "Dwgs.User" user "User.Drawings")
		(19 "Cmts.User" user "User.Comments")
		(21 "Eco1.User" user "User.Eco1")
		(23 "Eco2.User" user "User.Eco2")
		(25 "Edge.Cuts" user "Board Geometry/Outline")
		(27 "Margin" user)
		(31 "F.CrtYd" user "Package Geometry/Place Bound Top")
		(29 "B.CrtYd" user "Package Geometry/Place Bound Bottom")
		(35 "F.Fab" user "Ref Des/Assembly Top")
		(33 "B.Fab" user "Ref Des/Assembly Bottom")
	)
	(footprint ""
		(layer "F.Cu")
		(at 87.269828 -45.765212)
		(property "Reference" "R16"
			(at 0 0 0)
			(layer "F.SilkS")
			(hide yes)
			(effects
				(font
					(size 1.27 1.27)
				)
			)
		)
		(property "Value" "10KR2F-2-GP"
			(at 0.064008 -3.993896 0)
			(unlocked yes)
			(layer "F.Fab")
			(hide yes)
			(effects
				(font
					(size 1.016 1.016)
					(thickness 0.1524)
				)
			)
		)
		(property "Device Type" "R402H16"
			(at 0.064008 -5.517896 0)
			(unlocked yes)
			(layer "F.Fab")
			(hide yes)
			(effects
				(font
					(size 1.016 1.016)
					(thickness 0.1524)
				)
			)
		)
		(duplicate_pad_numbers_are_jumpers no)
		(fp_line
			(start -0.508 -0.9398)
			(end -0.508 0.9398)
			(stroke
				(width 0.1524)
				(type default)
			)
			(layer "F.SilkS")
		)
		(fp_line
			(start 0.508 -0.9398)
			(end -0.508 -0.9398)
			(stroke
				(width 0.1524)
				(type default)
			)
			(layer "F.SilkS")
		)
		(fp_rect
			(start -0.508 0.9398)
			(end 0.508 -0.9398)
			(stroke
				(width 0)
				(type default)
			)
			(fill no)
			(layer "F.CrtYd")
		)
		(fp_rect
			(start -0.508 0.9398)
			(end 0.508 -0.9398)
			(stroke
				(width 0)
				(type default)
			)
			(fill no)
			(layer "F.Fab")
		)
		(pad "1" smd custom
			(at 0 -0.4445)
			(size 0.1397 0.1397)
			(layers "F.Cu" "F.Mask" "F.Paste")
			(net "P3V3_STBY")
			(options
				(clearance outline)
				(anchor circle)
			)
			(primitives
				(gr_poly
					(pts
						(arc
							(start -0.1778 -0.2794)
							(mid -0.249642 -0.249642)
							(end -0.2794 -0.1778)
						)
						(arc
							(start -0.2794 0.1778)
							(mid -0.249642 0.249642)
							(end -0.1778 0.2794)
						)
						(arc
							(start 0.1778 0.2794)
							(mid 0.249642 0.249642)
							(end 0.2794 0.1778)
						)
						(arc
							(start 0.2794 -0.1778)
							(mid 0.249642 -0.249642)
							(end 0.1778 -0.2794)
						)
					)
					(width 0)
					(fill yes)
				)
			)
		)
		(pad "2" smd custom
			(at 0 0.4445)
			(size 0.1397 0.1397)
			(layers "F.Cu" "F.Mask" "F.Paste")
			(net "MEZZA_PRSNT1_N")
			(options
				(clearance outline)
				(anchor circle)
			)
			(primitives
				(gr_poly
					(pts
						(arc
							(start -0.1778 -0.2794)
							(mid -0.249642 -0.249642)
							(end -0.2794 -0.1778)
						)
						(arc
							(start -0.2794 0.1778)
							(mid -0.249642 0.249642)
							(end -0.1778 0.2794)
						)
						(arc
							(start 0.1778 0.2794)
							(mid 0.249642 0.249642)
							(end 0.2794 0.1778)
						)
						(arc
							(start 0.2794 -0.1778)
							(mid 0.249642 -0.249642)
							(end 0.1778 -0.2794)
						)
					)
					(width 0)
					(fill yes)
				)
			)
		)
	)
	(footprint ""
		(layer "F.Cu")
		(at 84.863178 -72.543416 90)
		(property "Reference" "VIA9"
			(at 0 0 90)
			(layer "F.SilkS")
			(hide yes)
			(effects
				(font
					(size 1.27 1.27)
				)
			)
		)
		(property "Value" "85OHM-8L-1D6MM-L16L18-GP"
			(at 4.064 0.6096 90)
			(unlocked yes)
			(layer "F.Fab")
			(hide yes)
			(effects
				(font
					(size 1.016 1.016)
					(thickness 0.1524)
				)
			)
		)
		(property "Device Type" "VIA-PCIE-4P-368076"
			(at 4.064 -0.9144 90)
			(unlocked yes)
			(layer "F.Fab")
			(hide yes)
			(effects
				(font
					(size 1.016 1.016)
					(thickness 0.1524)
				)
			)
		)
		(duplicate_pad_numbers_are_jumpers no)
		(fp_rect
			(start -1.8415 0.381)
			(end 1.8415 -0.381)
			(stroke
				(width 0)
				(type default)
			)
			(fill no)
			(layer "F.CrtYd")
		)
		(fp_rect
			(start -1.8415 0.381)
			(end 1.8415 -0.381)
			(stroke
				(width 0)
				(type default)
			)
			(fill no)
			(layer "F.Fab")
		)
		(pad "1" thru_hole circle
			(at -1.4605 0 90)
			(size 0.508 0.508)
			(drill 0.254)
			(layers "*.Cu" "*.Mask")
			(remove_unused_layers no)
			(net "GND")
			(clearance 0.127)
			(thermal_gap 0.127)
		)
		(pad "2" thru_hole circle
			(at -0.4445 0 90)
			(size 0.508 0.508)
			(drill 0.254)
			(layers "*.Cu" "*.Mask")
			(remove_unused_layers no)
			(net "PCIE_IOM_TO_COMP_16_DP")
			(clearance 0.127)
			(thermal_gap 0.127)
		)
		(pad "3" thru_hole circle
			(at 0.4445 0 90)
			(size 0.508 0.508)
			(drill 0.254)
			(layers "*.Cu" "*.Mask")
			(remove_unused_layers no)
			(net "PCIE_IOM_TO_COMP_16_DN")
			(clearance 0.127)
			(thermal_gap 0.127)
		)
		(pad "4" thru_hole circle
			(at 1.4605 0 90)
			(size 0.508 0.508)
			(drill 0.254)
			(layers "*.Cu" "*.Mask")
			(remove_unused_layers no)
			(net "GND")
			(clearance 0.127)
			(thermal_gap 0.127)
		)
	)
	(footprint ""
		(layer "F.Cu")
		(at 92.0242 -179.5018 -90)
		(property "Reference" "U106"
			(at 0 0 270)
			(layer "F.SilkS")
			(hide yes)
			(effects
				(font
					(size 1.27 1.27)
				)
			)
		)
		(property "Value" "SNLVC1G14DBVR-GP"
			(at 0 -5.1308 270)
			(unlocked yes)
			(layer "F.Fab")
			(hide yes)
			(effects
				(font
					(size 1.016 1.016)
					(thickness 0.1524)
				)
			)
		)
		(property "Device Type" "SOT-23-5H58"
			(at 0 -6.7564 270)
			(unlocked yes)
			(layer "F.Fab")
			(hide yes)
			(effects
				(font
					(size 1.016 1.016)
					(thickness 0.1524)
				)
			)
		)
		(duplicate_pad_numbers_are_jumpers no)
		(fp_line
			(start -1.778 2.286)
			(end -0.254 2.286)
			(stroke
				(width 0.1524)
				(type default)
			)
			(layer "F.SilkS")
		)
		(fp_line
			(start -1.778 2.286)
			(end 1.778 2.286)
			(stroke
				(width 0.1524)
				(type default)
			)
			(layer "F.SilkS")
		)
		(fp_line
			(start -0.254 2.286)
			(end 1.778 2.286)
			(stroke
				(width 0.1524)
				(type default)
			)
			(layer "F.SilkS")
		)
		(fp_line
			(start 1.778 2.286)
			(end 1.778 -2.286)
			(stroke
				(width 0.1524)
				(type default)
			)
			(layer "F.SilkS")
		)
		(fp_line
			(start -1.7272 2.2352)
			(end -1.7272 0.762)
			(stroke
				(width 0.3302)
				(type default)
			)
			(layer "F.SilkS")
		)
		(fp_line
			(start -0.7112 2.2352)
			(end -1.7272 2.2352)
			(stroke
				(width 0.3302)
				(type default)
			)
			(layer "F.SilkS")
		)
		(fp_line
			(start -1.778 -2.286)
			(end -1.778 2.286)
			(stroke
				(width 0.1524)
				(type default)
			)
			(layer "F.SilkS")
		)
		(fp_line
			(start 1.778 -2.286)
			(end -1.778 -2.286)
			(stroke
				(width 0.1524)
				(type default)
			)
			(layer "F.SilkS")
		)
		(fp_poly
			(pts
				(xy -0.9652 2.4384) (xy -1.3208 2.794) (xy -0.6096 2.794)
			)
			(stroke
				(width 0)
				(type default)
			)
			(fill yes)
			(layer "F.SilkS")
		)
		(fp_rect
			(start -1.778 2.286)
			(end 1.778 -2.286)
			(stroke
				(width 0)
				(type default)
			)
			(fill no)
			(layer "F.CrtYd")
		)
		(fp_rect
			(start -1.778 2.286)
			(end 1.778 -2.286)
			(stroke
				(width 0)
				(type default)
			)
			(fill no)
			(layer "F.Fab")
		)
		(pad "1" smd rect
			(at -0.94996 1.143 270)
			(size 0.508 1.524)
			(layers "F.Cu" "F.Mask" "F.Paste")
			(net "Net_132")
		)
		(pad "2" smd rect
			(at 0 1.143 270)
			(size 0.508 1.524)
			(layers "F.Cu" "F.Mask" "F.Paste")
			(net "PWRGD_P3V3_STBY")
		)
		(pad "3" smd rect
			(at 0.94996 1.143 270)
			(size 0.508 1.524)
			(layers "F.Cu" "F.Mask" "F.Paste")
			(net "GND")
		)
		(pad "4" smd rect
			(at 0.94996 -1.143 270)
			(size 0.508 1.524)
			(layers "F.Cu" "F.Mask" "F.Paste")
			(net "PWRGD_P3V3_STBY_N")
		)
		(pad "5" smd rect
			(at -0.94996 -1.143 270)
			(size 0.508 1.524)
			(layers "F.Cu" "F.Mask" "F.Paste")
			(net "P3V3_STBY")
		)
	)
	(footprint ""
		(layer "F.Cu")
		(at 88.813894 -63.755016 -90)
		(property "Reference" "R8"
			(at 0 0 270)
			(layer "F.SilkS")
			(hide yes)
			(effects
				(font
					(size 1.27 1.27)
				)
			)
		)
		(property "Value" "0R2J-2-GP"
			(at 0.064008 -3.993896 270)
			(unlocked yes)
			(layer "F.Fab")
			(hide yes)
			(effects
				(font
					(size 1.016 1.016)
					(thickness 0.1524)
				)
			)
		)
		(property "Device Type" "R402H16"
			(at 0.064008 -5.517896 270)
			(unlocked yes)
			(layer "F.Fab")
			(hide yes)
			(effects
				(font
					(size 1.016 1.016)
					(thickness 0.1524)
				)
			)
		)
		(duplicate_pad_numbers_are_jumpers no)
		(fp_line
			(start -0.508 -0.9398)
			(end -0.508 0.9398)
			(stroke
				(width 0.1524)
				(type default)
			)
			(layer "F.SilkS")
		)
		(fp_line
			(start 0.508 -0.9398)
			(end -0.508 -0.9398)
			(stroke
				(width 0.1524)
				(type default)
			)
			(layer "F.SilkS")
		)
		(fp_rect
			(start -0.508 0.9398)
			(end 0.508 -0.9398)
			(stroke
				(width 0)
				(type default)
			)
			(fill no)
			(layer "F.CrtYd")
		)
		(fp_rect
			(start -0.508 0.9398)
			(end 0.508 -0.9398)
			(stroke
				(width 0)
				(type default)
			)
			(fill no)
			(layer "F.Fab")
		)
		(pad "1" smd custom
			(at 0 -0.4445 270)
			(size 0.1397 0.1397)
			(layers "F.Cu" "F.Mask" "F.Paste")
			(net "PCIE_COMP_TO_IOM_RST_4")
			(options
				(clearance outline)
				(anchor circle)
			)
			(primitives
				(gr_poly
					(pts
						(arc
							(start -0.1778 -0.2794)
							(mid -0.249642 -0.249642)
							(end -0.2794 -0.1778)
						)
						(arc
							(start -0.2794 0.1778)
							(mid -0.249642 0.249642)
							(end -0.1778 0.2794)
						)
						(arc
							(start 0.1778 0.2794)
							(mid 0.249642 0.249642)
							(end 0.2794 0.1778)
						)
						(arc
							(start 0.2794 -0.1778)
							(mid 0.249642 -0.249642)
							(end 0.1778 -0.2794)
						)
					)
					(width 0)
					(fill yes)
				)
			)
		)
		(pad "2" smd custom
			(at 0 0.4445 270)
			(size 0.1397 0.1397)
			(layers "F.Cu" "F.Mask" "F.Paste")
			(net "PCIE_COMP_TO_IOM_RST_4_R")
			(options
				(clearance outline)
				(anchor circle)
			)
			(primitives
				(gr_poly
					(pts
						(arc
							(start -0.1778 -0.2794)
							(mid -0.249642 -0.249642)
							(end -0.2794 -0.1778)
						)
						(arc
							(start -0.2794 0.1778)
							(mid -0.249642 0.249642)
							(end -0.1778 0.2794)
						)
						(arc
							(start 0.1778 0.2794)
							(mid 0.249642 0.249642)
							(end 0.2794 0.1778)
						)
						(arc
							(start 0.2794 -0.1778)
							(mid 0.249642 -0.249642)
							(end 0.1778 -0.2794)
						)
					)
					(width 0)
					(fill yes)
				)
			)
		)
	)
	(footprint ""
		(layer "F.Cu")
		(at 222.293688 -23.022052 -90)
		(property "Reference" "C168"
			(at 0 0 270)
			(layer "F.SilkS")
			(hide yes)
			(effects
				(font
					(size 1.27 1.27)
				)
			)
		)
		(property "Value" "ST150U16VDM-3-GP"
			(at 0 -9.6012 270)
			(unlocked yes)
			(layer "F.Fab")
			(hide yes)
			(effects
				(font
					(size 1.016 1.016)
					(thickness 0.1524)
				)
			)
		)
		(property "Device Type" "CT7343H119"
			(at 0 -11.1252 270)
			(unlocked yes)
			(layer "F.Fab")
			(hide yes)
			(effects
				(font
					(size 1.016 1.016)
					(thickness 0.1524)
				)
			)
		)
		(duplicate_pad_numbers_are_jumpers no)
		(fp_line
			(start -2.286 4.8768)
			(end -2.286 2.032)
			(stroke
				(width 0.1524)
				(type default)
			)
			(layer "F.SilkS")
		)
		(fp_line
			(start 2.286 4.8768)
			(end -2.286 4.8768)
			(stroke
				(width 0.1524)
				(type default)
			)
			(layer "F.SilkS")
		)
		(fp_line
			(start 2.286 2.032)
			(end 2.286 4.8768)
			(stroke
				(width 0.1524)
				(type default)
			)
			(layer "F.SilkS")
		)
		(fp_line
			(start 2.286 -2.032)
			(end 2.286 -4.8768)
			(stroke
				(width 0.1524)
				(type default)
			)
			(layer "F.SilkS")
		)
		(fp_line
			(start 2.1082 -4.699)
			(end -2.1082 -4.699)
			(stroke
				(width 0.508)
				(type default)
			)
			(layer "F.SilkS")
		)
		(fp_line
			(start -2.286 -4.8768)
			(end -2.286 -2.032)
			(stroke
				(width 0.1524)
				(type default)
			)
			(layer "F.SilkS")
		)
		(fp_line
			(start 2.286 -4.8768)
			(end -2.286 -4.8768)
			(stroke
				(width 0.1524)
				(type default)
			)
			(layer "F.SilkS")
		)
		(fp_rect
			(start -2.1463 3.6449)
			(end 2.1463 -3.6449)
			(stroke
				(width 0)
				(type default)
			)
			(fill no)
			(layer "F.CrtYd")
		)
		(fp_poly
			(pts
				(xy -2.54 4.953) (xy -2.54 4.2926) (xy -3.81 4.2926) (xy -3.81 -4.2926) (xy -2.54 -4.2926) (xy -2.54 -4.953)
				(xy 2.54 -4.953) (xy 2.54 -4.2926) (xy 3.81 -4.2926) (xy 3.81 -1.6256) (xy 2.1463 -1.6256) (xy 2.1463 -3.6449)
				(xy -2.1463 -3.6449) (xy -2.1463 3.6449) (xy 2.1463 3.6449) (xy 2.1463 -1.6129) (xy 3.81 -1.6129)
				(xy 3.81 4.2926) (xy 2.54 4.2926) (xy 2.54 4.953)
			)
			(stroke
				(width 0)
				(type default)
			)
			(fill no)
			(layer "F.CrtYd")
		)
		(fp_rect
			(start -2.54 4.953)
			(end 2.54 -4.953)
			(stroke
				(width 0)
				(type default)
			)
			(fill no)
			(layer "F.Fab")
		)
		(fp_rect
			(start -3.81 4.2926)
			(end -2.54 -4.2926)
			(stroke
				(width 0)
				(type default)
			)
			(fill no)
			(layer "F.Fab")
		)
		(fp_rect
			(start 2.54 4.2926)
			(end 3.81 -4.2926)
			(stroke
				(width 0)
				(type default)
			)
			(fill no)
			(layer "F.Fab")
		)
		(pad "1" smd rect
			(at 0 -3.1496 270)
			(size 2.413 2.286)
			(layers "F.Cu" "F.Mask" "F.Paste")
			(net "P5V_STBY")
		)
		(pad "2" smd rect
			(at 0 3.1496 270)
			(size 2.413 2.286)
			(layers "F.Cu" "F.Mask" "F.Paste")
			(net "GND")
		)
		(zone
			(layer "F.Cu")
			(hatch none 0.5)
			(connect_pads
				(clearance 0)
			)
			(min_thickness 0.25)
			(keepout
				(tracks allowed)
				(vias not_allowed)
				(pads allowed)
				(copperpour not_allowed)
				(footprints allowed)
			)
			(placement
				(enabled no)
				(sheetname "")
			)
			(fill
				(thermal_gap 0.5)
				(thermal_bridge_width 0.5)
				(island_removal_mode 0)
			)
			(polygon
				(pts
					(xy 217.696288 -24.533352) (xy 217.696288 -21.510752) (xy 220.591888 -21.510752) (xy 220.922088 -21.510752)
					(xy 220.922088 -24.533352) (xy 220.591888 -24.533352)
				)
			)
		)
		(zone
			(layer "F.Cu")
			(hatch none 0.5)
			(connect_pads
				(clearance 0)
			)
			(min_thickness 0.25)
			(keepout
				(tracks allowed)
				(vias not_allowed)
				(pads allowed)
				(copperpour not_allowed)
				(footprints allowed)
			)
			(placement
				(enabled no)
				(sheetname "")
			)
			(fill
				(thermal_gap 0.5)
				(thermal_bridge_width 0.5)
				(island_removal_mode 0)
			)
			(polygon
				(pts
					(xy 223.982788 -21.510752) (xy 226.891088 -21.510752) (xy 226.891088 -24.533352) (xy 223.995488 -24.533352)
					(xy 223.665288 -24.533352) (xy 223.665288 -21.510752)
				)
			)
		)
	)
	(footprint ""
		(layer "F.Cu")
		(at 215.266524 -86.42096 -90)
		(property "Reference" "C652"
			(at 0 0 270)
			(layer "F.SilkS")
			(hide yes)
			(effects
				(font
					(size 1.27 1.27)
				)
			)
		)
		(property "Value" "SCD1U50V3KX-GP"
			(at 0 -2.8194 270)
			(unlocked yes)
			(layer "F.Fab")
			(hide yes)
			(effects
				(font
					(size 1.016 1.016)
					(thickness 0.1524)
				)
			)
		)
		(property "Device Type" "C603H36"
			(at 0 -4.3434 270)
			(unlocked yes)
			(layer "F.Fab")
			(hide yes)
			(effects
				(font
					(size 1.016 1.016)
					(thickness 0.1524)
				)
			)
		)
		(duplicate_pad_numbers_are_jumpers no)
		(fp_line
			(start 0.508 0)
			(end -0.508 0)
			(stroke
				(width 0.2032)
				(type default)
			)
			(layer "F.SilkS")
		)
		(fp_rect
			(start -0.5842 1.3335)
			(end 0.5842 -1.3335)
			(stroke
				(width 0)
				(type default)
			)
			(fill no)
			(layer "F.CrtYd")
		)
		(fp_rect
			(start -0.5842 1.3335)
			(end 0.5842 -1.3335)
			(stroke
				(width 0)
				(type default)
			)
			(fill no)
			(layer "F.Fab")
		)
		(pad "1" smd custom
			(at 0 -0.762 270)
			(size 0.2159 0.2159)
			(layers "F.Cu" "F.Mask" "F.Paste")
			(net "P3V3_M2")
			(options
				(clearance outline)
				(anchor circle)
			)
			(primitives
				(gr_poly
					(pts
						(arc
							(start -0.3302 -0.4318)
							(mid -0.402042 -0.402042)
							(end -0.4318 -0.3302)
						)
						(arc
							(start -0.4318 0.3302)
							(mid -0.402042 0.402042)
							(end -0.3302 0.4318)
						)
						(arc
							(start 0.3302 0.4318)
							(mid 0.402042 0.402042)
							(end 0.4318 0.3302)
						)
						(arc
							(start 0.4318 -0.3302)
							(mid 0.402042 -0.402042)
							(end 0.3302 -0.4318)
						)
					)
					(width 0)
					(fill yes)
				)
			)
		)
		(pad "2" smd custom
			(at 0 0.762 270)
			(size 0.2159 0.2159)
			(layers "F.Cu" "F.Mask" "F.Paste")
			(net "P3V3_M2_LL_R")
			(options
				(clearance outline)
				(anchor circle)
			)
			(primitives
				(gr_poly
					(pts
						(arc
							(start -0.3302 -0.4318)
							(mid -0.402042 -0.402042)
							(end -0.4318 -0.3302)
						)
						(arc
							(start -0.4318 0.3302)
							(mid -0.402042 0.402042)
							(end -0.3302 0.4318)
						)
						(arc
							(start 0.3302 0.4318)
							(mid 0.402042 0.402042)
							(end 0.4318 0.3302)
						)
						(arc
							(start 0.4318 -0.3302)
							(mid 0.402042 -0.402042)
							(end 0.3302 -0.4318)
						)
					)
					(width 0)
					(fill yes)
				)
			)
		)
	)
	(footprint ""
		(layer "F.Cu")
		(at 174.60849 -140.54709 -135)
		(property "Reference" "VIA62"
			(at 0 0 225)
			(layer "F.SilkS")
			(hide yes)
			(effects
				(font
					(size 1.27 1.27)
				)
			)
		)
		(property "Value" "85OHM-8L-1D6MM-L16L18-GP"
			(at 4.064105 0.609655 225)
			(unlocked yes)
			(layer "F.Fab")
			(hide yes)
			(effects
				(font
					(size 1.016 1.016)
					(thickness 0.1524)
				)
			)
		)
		(property "Device Type" "VIA-PCIE-4P-368076"
			(at 4.064105 -0.914474 225)
			(unlocked yes)
			(layer "F.Fab")
			(hide yes)
			(effects
				(font
					(size 1.016 1.016)
					(thickness 0.1524)
				)
			)
		)
		(duplicate_pad_numbers_are_jumpers no)
		(fp_poly
			(pts
				(xy -1.841491 -0.381057) (xy 1.841509 -0.381058) (xy 1.841508 0.380942) (xy -1.841491 0.380942)
			)
			(stroke
				(width 0)
				(type default)
			)
			(fill no)
			(layer "F.CrtYd")
		)
		(fp_poly
			(pts
				(xy -1.841491 -0.381057) (xy 1.841509 -0.381058) (xy 1.841508 0.380942) (xy -1.841491 0.380942)
			)
			(stroke
				(width 0)
				(type default)
			)
			(fill no)
			(layer "F.Fab")
		)
		(pad "1" thru_hole circle
			(at -1.460499 0 225)
			(size 0.508 0.508)
			(drill 0.254)
			(layers "*.Cu" "*.Mask")
			(remove_unused_layers no)
			(net "GND")
			(clearance 0.127)
			(thermal_gap 0.127)
		)
		(pad "2" thru_hole circle
			(at -0.4445 0 225)
			(size 0.508 0.508)
			(drill 0.254)
			(layers "*.Cu" "*.Mask")
			(remove_unused_layers no)
			(net "PCIE_COMP_TO_IOM_14_DP")
			(clearance 0.127)
			(thermal_gap 0.127)
		)
		(pad "3" thru_hole circle
			(at 0.4445 0 225)
			(size 0.508 0.508)
			(drill 0.254)
			(layers "*.Cu" "*.Mask")
			(remove_unused_layers no)
			(net "PCIE_COMP_TO_IOM_14_DN")
			(clearance 0.127)
			(thermal_gap 0.127)
		)
		(pad "4" thru_hole circle
			(at 1.460499 0 225)
			(size 0.508 0.508)
			(drill 0.254)
			(layers "*.Cu" "*.Mask")
			(remove_unused_layers no)
			(net "GND")
			(clearance 0.127)
			(thermal_gap 0.127)
		)
	)
)
